# S9S_MB_2U (Grand Teton) — schematic netlist excerpt (pin names and nets, part order shuffled) for the footprints in the layout excerpt that follows; sources: Cadence DE-HDL packaged netlist, KiCad conversion of 03242023_DA0F0TMBIJ0_F0T_Motherboard_J_brd_V01_OCP.brd

H127  HOLE  EMPTY  pkg TH  page 311 : \1\ = NC
C262  Q_CAP  10UF 6.3V 20% X6S  pkg C0402  page 77 : A = PVCCIN_CPU1 ; B = GND
R3976  Q_RES  100K 1% EMPTY  pkg 0402LF  page 192 : A = P3V3_AUX ; B = P12V_E1S_FAULT_0

(kicad_pcb
	(version 20260206)
	(generator "pcbnew")
	(generator_version "10.0")
	(general
		(thickness 1.6)
		(legacy_teardrops no)
	)
	(paper "A4")
	(title_block
		(title "03242023_DA0F0TMBIJ0_F0T_Motherboard_J_brd_V01_OCP.brd")
		(comment 1 "Grand Teton / footprints 3903-3905 of 6105")
	)
	(layers
		(0 "F.Cu" signal "TOP")
		(4 "In1.Cu" signal "GND")
		(6 "In2.Cu" signal "IN1")
		(8 "In3.Cu" signal "GND1")
		(10 "In4.Cu" signal "IN2")
		(12 "In5.Cu" signal "GND2")
		(14 "In6.Cu" signal "IN3")
		(16 "In7.Cu" signal "GND3")
		(18 "In8.Cu" signal "VCC")
		(20 "In9.Cu" signal "VCC1")
		(22 "In10.Cu" signal "GND4")
		(24 "In11.Cu" signal "IN4")
		(26 "In12.Cu" signal "GND5")
		(28 "In13.Cu" signal "IN5")
		(30 "In14.Cu" signal "GND6")
		(32 "In15.Cu" signal "IN6")
		(34 "In16.Cu" signal "GND7")
		(2 "B.Cu" signal "BOTTOM")
		(9 "F.Adhes" user "F.Adhesive")
		(11 "B.Adhes" user "B.Adhesive")
		(13 "F.Paste" user "Package Geometry/Pastemask Top")
		(15 "B.Paste" user "Package Geometry/Pastemask Bottom")
		(5 "F.SilkS" user "Ref Des/Silkscreen Top")
		(7 "B.SilkS" user "Ref Des/Silkscreen Bottom")
		(1 "F.Mask" user "Board Geometry/Soldermask Top")
		(3 "B.Mask" user "Board Geometry/Soldermask Bottom")
		(17 "Dwgs.User" user "User.Drawings")
		(19 "Cmts.User" user "User.Comments")
		(21 "Eco1.User" user "User.Eco1")
		(23 "Eco2.User" user "User.Eco2")
		(25 "Edge.Cuts" user "Board Geometry/Outline")
		(27 "Margin" user)
		(31 "F.CrtYd" user "Package Geometry/Place Bound Top")
		(29 "B.CrtYd" user "Package Geometry/Place Bound Bottom")
		(35 "F.Fab" user "Ref Des/Assembly Top")
		(33 "B.Fab" user "Ref Des/Assembly Bottom")
	)
	(footprint ""
		(layer "F.Cu")
		(at 106.328464 -238.162592 -90)
		(property "Reference" "C262"
			(at 0 0 270)
			(layer "F.SilkS")
			(hide yes)
			(effects
				(font
					(size 1.27 1.27)
				)
			)
		)
		(property "Value" ""
			(at 0 0 270)
			(layer "F.Fab")
			(effects
				(font
					(size 1.27 1.27)
				)
			)
		)
		(duplicate_pad_numbers_are_jumpers no)
		(fp_line
			(start -0.7874 0.4064)
			(end -0.7874 -0.4064)
			(stroke
				(width 0.1524)
				(type default)
			)
			(layer "F.SilkS")
		)
		(fp_line
			(start 0.7874 0.4064)
			(end -0.7874 0.4064)
			(stroke
				(width 0.1524)
				(type default)
			)
			(layer "F.SilkS")
		)
		(fp_line
			(start -0.7874 -0.4064)
			(end 0.7874 -0.4064)
			(stroke
				(width 0.1524)
				(type default)
			)
			(layer "F.SilkS")
		)
		(fp_line
			(start 0.7874 -0.4064)
			(end 0.7874 0.4064)
			(stroke
				(width 0.1524)
				(type default)
			)
			(layer "F.SilkS")
		)
		(fp_line
			(start -0.67945 0.3048)
			(end -0.67945 -0.305054)
			(stroke
				(width 0.1)
				(type default)
			)
			(layer "F.Fab")
		)
		(fp_line
			(start -0.12065 0.3048)
			(end -0.67945 0.3048)
			(stroke
				(width 0.1)
				(type default)
			)
			(layer "F.Fab")
		)
		(fp_line
			(start 0.120396 0.3048)
			(end 0.120396 0.2794)
			(stroke
				(width 0.1)
				(type default)
			)
			(layer "F.Fab")
		)
		(fp_line
			(start 0.67945 0.3048)
			(end 0.120396 0.3048)
			(stroke
				(width 0.1)
				(type default)
			)
			(layer "F.Fab")
		)
		(fp_line
			(start -0.12065 0.2794)
			(end -0.12065 0.3048)
			(stroke
				(width 0.1)
				(type default)
			)
			(layer "F.Fab")
		)
		(fp_line
			(start 0.120396 0.2794)
			(end -0.12065 0.2794)
			(stroke
				(width 0.1)
				(type default)
			)
			(layer "F.Fab")
		)
		(fp_line
			(start -0.12065 -0.2794)
			(end 0.12065 -0.2794)
			(stroke
				(width 0.1)
				(type default)
			)
			(layer "F.Fab")
		)
		(fp_line
			(start 0.12065 -0.2794)
			(end 0.12065 -0.3048)
			(stroke
				(width 0.1)
				(type default)
			)
			(layer "F.Fab")
		)
		(fp_line
			(start 0.12065 -0.3048)
			(end 0.67945 -0.3048)
			(stroke
				(width 0.1)
				(type default)
			)
			(layer "F.Fab")
		)
		(fp_line
			(start 0.67945 -0.3048)
			(end 0.67945 0.3048)
			(stroke
				(width 0.1)
				(type default)
			)
			(layer "F.Fab")
		)
		(fp_line
			(start -0.67945 -0.305054)
			(end -0.12065 -0.305054)
			(stroke
				(width 0.1)
				(type default)
			)
			(layer "F.Fab")
		)
		(fp_line
			(start -0.12065 -0.305054)
			(end -0.12065 -0.2794)
			(stroke
				(width 0.1)
				(type default)
			)
			(layer "F.Fab")
		)
		(pad "1" smd circle
			(at -0.40005 0 270)
			(size 0 0)
			(layers "F.Cu" "F.Mask" "F.Paste")
			(net "PVCCIN_CPU1")
		)
		(pad "2" smd circle
			(at 0.40005 0 270)
			(size 0 0)
			(layers "F.Cu" "F.Mask" "F.Paste")
			(net "GND")
		)
	)
	(footprint ""
		(layer "F.Cu")
		(at 254 -37.667946 180)
		(property "Reference" "R3976"
			(at 0 0 180)
			(layer "F.SilkS")
			(hide yes)
			(effects
				(font
					(size 1.27 1.27)
				)
			)
		)
		(property "Value" ""
			(at 0 0 180)
			(layer "F.Fab")
			(effects
				(font
					(size 1.27 1.27)
				)
			)
		)
		(duplicate_pad_numbers_are_jumpers no)
		(fp_line
			(start 0.7874 0.4064)
			(end -0.7874 0.4064)
			(stroke
				(width 0.1524)
				(type default)
			)
			(layer "F.SilkS")
		)
		(fp_line
			(start 0.7874 -0.4064)
			(end 0.7874 0.4064)
			(stroke
				(width 0.1524)
				(type default)
			)
			(layer "F.SilkS")
		)
		(fp_line
			(start -0.7874 0.4064)
			(end -0.7874 -0.4064)
			(stroke
				(width 0.1524)
				(type default)
			)
			(layer "F.SilkS")
		)
		(fp_line
			(start -0.7874 -0.4064)
			(end 0.7874 -0.4064)
			(stroke
				(width 0.1524)
				(type default)
			)
			(layer "F.SilkS")
		)
		(fp_line
			(start 0.67945 0.3048)
			(end 0.120396 0.3048)
			(stroke
				(width 0.1)
				(type default)
			)
			(layer "F.Fab")
		)
		(fp_line
			(start 0.67945 -0.3048)
			(end 0.67945 0.3048)
			(stroke
				(width 0.1)
				(type default)
			)
			(layer "F.Fab")
		)
		(fp_line
			(start 0.12065 -0.2794)
			(end 0.12065 -0.3048)
			(stroke
				(width 0.1)
				(type default)
			)
			(layer "F.Fab")
		)
		(fp_line
			(start 0.12065 -0.3048)
			(end 0.67945 -0.3048)
			(stroke
				(width 0.1)
				(type default)
			)
			(layer "F.Fab")
		)
		(fp_line
			(start 0.120396 0.3048)
			(end 0.120396 0.2794)
			(stroke
				(width 0.1)
				(type default)
			)
			(layer "F.Fab")
		)
		(fp_line
			(start 0.120396 0.2794)
			(end -0.12065 0.2794)
			(stroke
				(width 0.1)
				(type default)
			)
			(layer "F.Fab")
		)
		(fp_line
			(start -0.12065 0.3048)
			(end -0.67945 0.3048)
			(stroke
				(width 0.1)
				(type default)
			)
			(layer "F.Fab")
		)
		(fp_line
			(start -0.12065 0.2794)
			(end -0.12065 0.3048)
			(stroke
				(width 0.1)
				(type default)
			)
			(layer "F.Fab")
		)
		(fp_line
			(start -0.12065 -0.2794)
			(end 0.12065 -0.2794)
			(stroke
				(width 0.1)
				(type default)
			)
			(layer "F.Fab")
		)
		(fp_line
			(start -0.12065 -0.305054)
			(end -0.12065 -0.2794)
			(stroke
				(width 0.1)
				(type default)
			)
			(layer "F.Fab")
		)
		(fp_line
			(start -0.67945 0.3048)
			(end -0.67945 -0.305054)
			(stroke
				(width 0.1)
				(type default)
			)
			(layer "F.Fab")
		)
		(fp_line
			(start -0.67945 -0.305054)
			(end -0.12065 -0.305054)
			(stroke
				(width 0.1)
				(type default)
			)
			(layer "F.Fab")
		)
		(pad "1" smd circle
			(at -0.40005 0 180)
			(size 0 0)
			(layers "F.Cu" "F.Mask" "F.Paste")
			(net "P3V3_AUX")
		)
		(pad "2" smd circle
			(at 0.40005 0 180)
			(size 0 0)
			(layers "F.Cu" "F.Mask" "F.Paste")
			(net "P12V_E1S_FAULT_0")
		)
	)
	(footprint ""
		(layer "F.Cu")
		(at 462.078832 -360.76382)
		(property "Reference" "H127"
			(at -3.766312 -6.887718 0)
			(unlocked yes)
			(layer "F.SilkS")
			(effects
				(font
					(size 0.7874 0.5842)
					(thickness 0.1524)
				)
				(justify left)
			)
		)
		(property "Value" ""
			(at 0 0 0)
			(layer "F.Fab")
			(effects
				(font
					(size 1.27 1.27)
				)
			)
		)
		(duplicate_pad_numbers_are_jumpers no)
		(fp_arc
			(start 4.69773 3.430016)
			(mid -5.81025 -0.291475)
			(end 5.017516 -2.942082)
			(stroke
				(width 0.1524)
				(type default)
			)
			(layer "F.SilkS")
		)
		(fp_arc
			(start 4.7879 3.303016)
			(mid -5.810958 -0.220995)
			(end 5.025136 -2.929128)
			(stroke
				(width 0.1524)
				(type default)
			)
			(layer "B.SilkS")
		)
		(fp_circle
			(center 0 0)
			(end 5.8166 0)
			(stroke
				(width 0.1)
				(type default)
			)
			(fill no)
			(layer "B.Fab")
		)
		(fp_circle
			(center 0 0)
			(end 5.8166 0)
			(stroke
				(width 0.1)
				(type default)
			)
			(fill no)
			(layer "F.Fab")
		)
		(pad "" np_thru_hole circle
			(at 0 0)
			(size 10.0076 10.0076)
			(drill 10.0076)
			(layers "*.Cu" "*.Mask")
			(clearance 0.381)
			(thermal_gap 0.381)
		)
		(zone
			(layers "F.Cu" "B.Cu" "In1.Cu" "In2.Cu" "In3.Cu" "In4.Cu" "In5.Cu" "In6.Cu"
				"In7.Cu" "In8.Cu" "In9.Cu" "In10.Cu" "In11.Cu" "In12.Cu" "In13.Cu" "In14.Cu"
				"In15.Cu" "In16.Cu"
			)
			(hatch none 0.5)
			(connect_pads
				(clearance 0)
			)
			(min_thickness 0.25)
			(keepout
				(tracks not_allowed)
				(vias allowed)
				(pads allowed)
				(copperpour not_allowed)
				(footprints allowed)
			)
			(placement
				(enabled no)
				(sheetname "")
			)
			(fill
				(thermal_gap 0.5)
				(thermal_bridge_width 0.5)
				(island_removal_mode 0)
			)
			(polygon
				(pts
					(arc
						(start 467.590632 -360.76382)
						(mid 456.567032 -360.76382)
						(end 467.590632 -360.76382)
					)
				)
			)
		)
	)
)
